(kicad_pcb
	(version 20260206)
	(generator "pcbnew")
	(generator_version "10.0")
	(general
		(thickness 1.6)
		(legacy_teardrops no)
	)
	(paper "A4")
	(title_block
		(title "Bryce Canyon_F.DPB_16315-1-OCP.brd")
		(comment 1 "Bryce Canyon / footprints 1288-1294 of 2223")
	)
	(layers
		(0 "F.Cu" signal "TOP")
		(4 "In1.Cu" signal "L2GND")
		(6 "In2.Cu" signal "L3")
		(8 "In3.Cu" signal "L4GND")
		(10 "In4.Cu" signal "L5")
		(12 "In5.Cu" signal "L6VCC")
		(14 "In6.Cu" signal "L7VCC")
		(16 "In7.Cu" signal "L8")
		(18 "In8.Cu" signal "L9GND")
		(20 "In9.Cu" signal "L10")
		(22 "In10.Cu" signal "L11GND")
		(2 "B.Cu" signal "BOTTOM")
		(9 "F.Adhes" user "F.Adhesive")
		(11 "B.Adhes" user "B.Adhesive")
		(13 "F.Paste" user "Package Geometry/Pastemask Top")
		(15 "B.Paste" user "Package Geometry/Pastemask Bottom")
		(5 "F.SilkS" user "Ref Des/Silkscreen Top")
		(7 "B.SilkS" user "Ref Des/Silkscreen Bottom")
		(1 "F.Mask" user "Board Geometry/Soldermask Top")
		(3 "B.Mask" user "Board Geometry/Soldermask Bottom")
		(17 "Dwgs.User" user "User.Drawings")
		(19 "Cmts.User" user "User.Comments")
		(21 "Eco1.User" user "User.Eco1")
		(23 "Eco2.User" user "User.Eco2")
		(25 "Edge.Cuts" user "Board Geometry/Outline")
		(27 "Margin" user)
		(31 "F.CrtYd" user "Package Geometry/Place Bound Top")
		(29 "B.CrtYd" user "Package Geometry/Place Bound Bottom")
		(35 "F.Fab" user "Ref Des/Assembly Top")
		(33 "B.Fab" user "Ref Des/Assembly Bottom")
	)
	(footprint ""
		(layer "F.Cu")
		(at 216.027 -381.762 180)
		(property "Reference" "R366"
			(at 0 0 180)
			(layer "F.SilkS")
			(hide yes)
			(effects
				(font
					(size 1.27 1.27)
				)
			)
		)
		(property "Value" "0R2J-2-GP"
			(at 0.064008 -3.993896 180)
			(unlocked yes)
			(layer "F.Fab")
			(hide yes)
			(effects
				(font
					(size 1.016 1.016)
					(thickness 0.1524)
				)
			)
		)
		(property "Device Type" "R402H16"
			(at 0.064008 -5.517896 180)
			(unlocked yes)
			(layer "F.Fab")
			(hide yes)
			(effects
				(font
					(size 1.016 1.016)
					(thickness 0.1524)
				)
			)
		)
		(duplicate_pad_numbers_are_jumpers no)
		(fp_line
			(start 0.508 -0.9398)
			(end -0.508 -0.9398)
			(stroke
				(width 0.1524)
				(type default)
			)
			(layer "F.SilkS")
		)
		(fp_line
			(start -0.508 -0.9398)
			(end -0.508 0.9398)
			(stroke
				(width 0.1524)
				(type default)
			)
			(layer "F.SilkS")
		)
		(fp_rect
			(start -0.508 0.9398)
			(end 0.508 -0.9398)
			(stroke
				(width 0)
				(type default)
			)
			(fill no)
			(layer "F.CrtYd")
		)
		(fp_rect
			(start -0.508 0.9398)
			(end 0.508 -0.9398)
			(stroke
				(width 0)
				(type default)
			)
			(fill no)
			(layer "F.Fab")
		)
		(pad "1" smd custom
			(at 0 -0.4445 180)
			(size 0.1397 0.1397)
			(layers "F.Cu" "F.Mask" "F.Paste")
			(net "SCC_FULL_PWR_EN_5V")
			(options
				(clearance outline)
				(anchor circle)
			)
			(primitives
				(gr_poly
					(pts
						(arc
							(start -0.1778 -0.2794)
							(mid -0.249642 -0.249642)
							(end -0.2794 -0.1778)
						)
						(arc
							(start -0.2794 0.1778)
							(mid -0.249642 0.249642)
							(end -0.1778 0.2794)
						)
						(arc
							(start 0.1778 0.2794)
							(mid 0.249642 0.249642)
							(end 0.2794 0.1778)
						)
						(arc
							(start 0.2794 -0.1778)
							(mid 0.249642 -0.249642)
							(end 0.1778 -0.2794)
						)
					)
					(width 0)
					(fill yes)
				)
			)
		)
		(pad "2" smd custom
			(at 0 0.4445 180)
			(size 0.1397 0.1397)
			(layers "F.Cu" "F.Mask" "F.Paste")
			(net "SCC_FULL_PWR_EN_5V_R")
			(options
				(clearance outline)
				(anchor circle)
			)
			(primitives
				(gr_poly
					(pts
						(arc
							(start -0.1778 -0.2794)
							(mid -0.249642 -0.249642)
							(end -0.2794 -0.1778)
						)
						(arc
							(start -0.2794 0.1778)
							(mid -0.249642 0.249642)
							(end -0.1778 0.2794)
						)
						(arc
							(start 0.1778 0.2794)
							(mid 0.249642 0.249642)
							(end 0.2794 0.1778)
						)
						(arc
							(start 0.2794 -0.1778)
							(mid 0.249642 -0.249642)
							(end 0.1778 -0.2794)
						)
					)
					(width 0)
					(fill yes)
				)
			)
		)
	)
	(footprint ""
		(layer "F.Cu")
		(at 240.23066 -241.849148 180)
		(property "Reference" "R128"
			(at 0 0 180)
			(layer "F.SilkS")
			(hide yes)
			(effects
				(font
					(size 1.27 1.27)
				)
			)
		)
		(property "Value" "100KR2F-L1-GP"
			(at 0.064008 -3.993896 180)
			(unlocked yes)
			(layer "F.Fab")
			(hide yes)
			(effects
				(font
					(size 1.016 1.016)
					(thickness 0.1524)
				)
			)
		)
		(property "Device Type" "R402H16"
			(at 0.064008 -5.517896 180)
			(unlocked yes)
			(layer "F.Fab")
			(hide yes)
			(effects
				(font
					(size 1.016 1.016)
					(thickness 0.1524)
				)
			)
		)
		(duplicate_pad_numbers_are_jumpers no)
		(fp_line
			(start 0.508 -0.9398)
			(end -0.508 -0.9398)
			(stroke
				(width 0.1524)
				(type default)
			)
			(layer "F.SilkS")
		)
		(fp_line
			(start -0.508 -0.9398)
			(end -0.508 0.9398)
			(stroke
				(width 0.1524)
				(type default)
			)
			(layer "F.SilkS")
		)
		(fp_rect
			(start -0.508 0.9398)
			(end 0.508 -0.9398)
			(stroke
				(width 0)
				(type default)
			)
			(fill no)
			(layer "F.CrtYd")
		)
		(fp_rect
			(start -0.508 0.9398)
			(end 0.508 -0.9398)
			(stroke
				(width 0)
				(type default)
			)
			(fill no)
			(layer "F.Fab")
		)
		(pad "1" smd custom
			(at 0 -0.4445 180)
			(size 0.1397 0.1397)
			(layers "F.Cu" "F.Mask" "F.Paste")
			(net "GPIO_VCC_U8")
			(options
				(clearance outline)
				(anchor circle)
			)
			(primitives
				(gr_poly
					(pts
						(arc
							(start -0.1778 -0.2794)
							(mid -0.249642 -0.249642)
							(end -0.2794 -0.1778)
						)
						(arc
							(start -0.2794 0.1778)
							(mid -0.249642 0.249642)
							(end -0.1778 0.2794)
						)
						(arc
							(start 0.1778 0.2794)
							(mid 0.249642 0.249642)
							(end 0.2794 0.1778)
						)
						(arc
							(start 0.2794 -0.1778)
							(mid 0.249642 -0.249642)
							(end 0.1778 -0.2794)
						)
					)
					(width 0)
					(fill yes)
				)
			)
		)
		(pad "2" smd custom
			(at 0 0.4445 180)
			(size 0.1397 0.1397)
			(layers "F.Cu" "F.Mask" "F.Paste")
			(net "GND")
			(options
				(clearance outline)
				(anchor circle)
			)
			(primitives
				(gr_poly
					(pts
						(arc
							(start -0.1778 -0.2794)
							(mid -0.249642 -0.249642)
							(end -0.2794 -0.1778)
						)
						(arc
							(start -0.2794 0.1778)
							(mid -0.249642 0.249642)
							(end -0.1778 0.2794)
						)
						(arc
							(start 0.1778 0.2794)
							(mid 0.249642 0.249642)
							(end 0.2794 0.1778)
						)
						(arc
							(start 0.2794 -0.1778)
							(mid 0.249642 -0.249642)
							(end 0.1778 -0.2794)
						)
					)
					(width 0)
					(fill yes)
				)
			)
		)
	)
	(footprint ""
		(layer "F.Cu")
		(at 383.08915 -158.939992 90)
		(property "Reference" "VIA9"
			(at 0 0 90)
			(layer "F.SilkS")
			(hide yes)
			(effects
				(font
					(size 1.27 1.27)
				)
			)
		)
		(property "Value" "100OHM-8L-1D6MM-L18L16-GP"
			(at -3.7211 -4.5085 90)
			(unlocked yes)
			(layer "F.Fab")
			(hide yes)
			(effects
				(font
					(size 1.016 1.016)
					(thickness 0.1524)
				)
			)
		)
		(property "Device Type" "VIA-PCIE-4P-394076"
			(at -3.7211 -6.0325 90)
			(unlocked yes)
			(layer "F.Fab")
			(hide yes)
			(effects
				(font
					(size 1.016 1.016)
					(thickness 0.1524)
				)
			)
		)
		(duplicate_pad_numbers_are_jumpers no)
		(fp_rect
			(start -1.9685 0.381)
			(end 1.9685 -0.381)
			(stroke
				(width 0)
				(type default)
			)
			(fill no)
			(layer "F.CrtYd")
		)
		(fp_rect
			(start -1.9685 0.381)
			(end 1.9685 -0.381)
			(stroke
				(width 0)
				(type default)
			)
			(fill no)
			(layer "F.Fab")
		)
		(pad "1" thru_hole circle
			(at -1.5875 0 90)
			(size 0.508 0.508)
			(drill 0.254)
			(layers "*.Cu" "*.Mask")
			(remove_unused_layers no)
			(net "GND")
			(clearance 0.127)
			(thermal_gap 0.127)
		)
		(pad "2" thru_hole circle
			(at -0.5715 0 90)
			(size 0.508 0.508)
			(drill 0.254)
			(layers "*.Cu" "*.Mask")
			(remove_unused_layers no)
			(net "PHY_SCC_A_TO_DRV_A_20_DP")
			(clearance 0.127)
			(thermal_gap 0.127)
		)
		(pad "3" thru_hole circle
			(at 0.5715 0 90)
			(size 0.508 0.508)
			(drill 0.254)
			(layers "*.Cu" "*.Mask")
			(remove_unused_layers no)
			(net "PHY_SCC_A_TO_DRV_A_20_DN")
			(clearance 0.127)
			(thermal_gap 0.127)
		)
		(pad "4" thru_hole circle
			(at 1.5875 0 90)
			(size 0.508 0.508)
			(drill 0.254)
			(layers "*.Cu" "*.Mask")
			(remove_unused_layers no)
			(net "GND")
			(clearance 0.127)
			(thermal_gap 0.127)
		)
	)
	(footprint ""
		(layer "F.Cu")
		(at 151.708866 -140.292074 -90)
		(property "Reference" "R1039"
			(at 0 0 270)
			(layer "F.SilkS")
			(hide yes)
			(effects
				(font
					(size 1.27 1.27)
				)
			)
		)
		(property "Value" "10R2F-L-GP"
			(at 0.064008 -3.993896 270)
			(unlocked yes)
			(layer "F.Fab")
			(hide yes)
			(effects
				(font
					(size 1.016 1.016)
					(thickness 0.1524)
				)
			)
		)
		(property "Device Type" "R402H14"
			(at 0.064008 -5.517896 270)
			(unlocked yes)
			(layer "F.Fab")
			(hide yes)
			(effects
				(font
					(size 1.016 1.016)
					(thickness 0.1524)
				)
			)
		)
		(duplicate_pad_numbers_are_jumpers no)
		(fp_line
			(start -0.508 -0.9398)
			(end -0.508 0.9398)
			(stroke
				(width 0.1524)
				(type default)
			)
			(layer "F.SilkS")
		)
		(fp_line
			(start 0.508 -0.9398)
			(end -0.508 -0.9398)
			(stroke
				(width 0.1524)
				(type default)
			)
			(layer "F.SilkS")
		)
		(fp_rect
			(start -0.508 0.9398)
			(end 0.508 -0.9398)
			(stroke
				(width 0)
				(type default)
			)
			(fill no)
			(layer "F.CrtYd")
		)
		(fp_rect
			(start -0.508 0.9398)
			(end 0.508 -0.9398)
			(stroke
				(width 0)
				(type default)
			)
			(fill no)
			(layer "F.Fab")
		)
		(pad "1" smd custom
			(at 0 -0.4445 270)
			(size 0.1397 0.1397)
			(layers "F.Cu" "F.Mask" "F.Paste")
			(net "P12V_A")
			(options
				(clearance outline)
				(anchor circle)
			)
			(primitives
				(gr_poly
					(pts
						(arc
							(start -0.1778 -0.2794)
							(mid -0.249642 -0.249642)
							(end -0.2794 -0.1778)
						)
						(arc
							(start -0.2794 0.1778)
							(mid -0.249642 0.249642)
							(end -0.1778 0.2794)
						)
						(arc
							(start 0.1778 0.2794)
							(mid 0.249642 0.249642)
							(end 0.2794 0.1778)
						)
						(arc
							(start 0.2794 -0.1778)
							(mid 0.249642 -0.249642)
							(end 0.1778 -0.2794)
						)
					)
					(width 0)
					(fill yes)
				)
			)
		)
		(pad "2" smd custom
			(at 0 0.4445 270)
			(size 0.1397 0.1397)
			(layers "F.Cu" "F.Mask" "F.Paste")
			(net "MB0_P12V_HS")
			(options
				(clearance outline)
				(anchor circle)
			)
			(primitives
				(gr_poly
					(pts
						(arc
							(start -0.1778 -0.2794)
							(mid -0.249642 -0.249642)
							(end -0.2794 -0.1778)
						)
						(arc
							(start -0.2794 0.1778)
							(mid -0.249642 0.249642)
							(end -0.1778 0.2794)
						)
						(arc
							(start 0.1778 0.2794)
							(mid 0.249642 0.249642)
							(end 0.2794 0.1778)
						)
						(arc
							(start 0.2794 -0.1778)
							(mid 0.249642 -0.249642)
							(end 0.1778 -0.2794)
						)
					)
					(width 0)
					(fill yes)
				)
			)
		)
	)
	(footprint ""
		(layer "F.Cu")
		(at 143.074898 -161.649918 180)
		(property "Reference" "D16"
			(at 0 0 180)
			(layer "F.SilkS")
			(hide yes)
			(effects
				(font
					(size 1.27 1.27)
				)
			)
		)
		(property "Value" "RB551V30-GP"
			(at 0 -6.7818 180)
			(unlocked yes)
			(layer "F.Fab")
			(hide yes)
			(effects
				(font
					(size 1.016 1.016)
					(thickness 0.1524)
				)
			)
		)
		(property "Device Type" "SOD323AKH38"
			(at 0 -8.6868 180)
			(unlocked yes)
			(layer "F.Fab")
			(hide yes)
			(effects
				(font
					(size 1.016 1.016)
					(thickness 0.1524)
				)
			)
		)
		(duplicate_pad_numbers_are_jumpers no)
		(fp_line
			(start 0.889 2.159)
			(end -0.889 2.159)
			(stroke
				(width 0.1524)
				(type default)
			)
			(layer "F.SilkS")
		)
		(fp_line
			(start 0.889 -1.9304)
			(end 0.889 2.159)
			(stroke
				(width 0.1524)
				(type default)
			)
			(layer "F.SilkS")
		)
		(fp_line
			(start 0.762 2.0574)
			(end -0.762 2.0574)
			(stroke
				(width 0.508)
				(type default)
			)
			(layer "F.SilkS")
		)
		(fp_line
			(start -0.889 2.159)
			(end -0.889 -1.9304)
			(stroke
				(width 0.1524)
				(type default)
			)
			(layer "F.SilkS")
		)
		(fp_line
			(start -0.889 -1.9304)
			(end 0.889 -1.9304)
			(stroke
				(width 0.1524)
				(type default)
			)
			(layer "F.SilkS")
		)
		(fp_rect
			(start -1.016 2.3114)
			(end 1.016 -2.0066)
			(stroke
				(width 0)
				(type default)
			)
			(fill no)
			(layer "F.CrtYd")
		)
		(fp_poly
			(pts
				(xy -1.016 -2.0066) (xy 1.016 -2.0066) (xy 1.016 2.3114) (xy -1.016 2.3114)
			)
			(stroke
				(width 0)
				(type default)
			)
			(fill no)
			(layer "F.Fab")
		)
		(pad "A" smd rect
			(at 0 -1.143 180)
			(size 0.5588 1.016)
			(layers "F.Cu" "F.Mask" "F.Paste")
			(net "SW_HDD_R16")
		)
		(pad "K" smd rect
			(at 0 1.143 180)
			(size 0.5588 1.016)
			(layers "F.Cu" "F.Mask" "F.Paste")
			(net "SW_HDD_N16")
		)
	)
	(footprint ""
		(layer "F.Cu")
		(at 234.0864 -248.9708 180)
		(property "Reference" "R31"
			(at 0 0 180)
			(layer "F.SilkS")
			(hide yes)
			(effects
				(font
					(size 1.27 1.27)
				)
			)
		)
		(property "Value" "4K7R2F-GP"
			(at 0.064008 -3.993896 180)
			(unlocked yes)
			(layer "F.Fab")
			(hide yes)
			(effects
				(font
					(size 1.016 1.016)
					(thickness 0.1524)
				)
			)
		)
		(property "Device Type" "R402H16"
			(at 0.064008 -5.517896 180)
			(unlocked yes)
			(layer "F.Fab")
			(hide yes)
			(effects
				(font
					(size 1.016 1.016)
					(thickness 0.1524)
				)
			)
		)
		(duplicate_pad_numbers_are_jumpers no)
		(fp_line
			(start 0.508 -0.9398)
			(end -0.508 -0.9398)
			(stroke
				(width 0.1524)
				(type default)
			)
			(layer "F.SilkS")
		)
		(fp_line
			(start -0.508 -0.9398)
			(end -0.508 0.9398)
			(stroke
				(width 0.1524)
				(type default)
			)
			(layer "F.SilkS")
		)
		(fp_rect
			(start -0.508 0.9398)
			(end 0.508 -0.9398)
			(stroke
				(width 0)
				(type default)
			)
			(fill no)
			(layer "F.CrtYd")
		)
		(fp_rect
			(start -0.508 0.9398)
			(end 0.508 -0.9398)
			(stroke
				(width 0)
				(type default)
			)
			(fill no)
			(layer "F.Fab")
		)
		(pad "1" smd custom
			(at 0 -0.4445 180)
			(size 0.1397 0.1397)
			(layers "F.Cu" "F.Mask" "F.Paste")
			(net "P3V3_STBY_A")
			(options
				(clearance outline)
				(anchor circle)
			)
			(primitives
				(gr_poly
					(pts
						(arc
							(start -0.1778 -0.2794)
							(mid -0.249642 -0.249642)
							(end -0.2794 -0.1778)
						)
						(arc
							(start -0.2794 0.1778)
							(mid -0.249642 0.249642)
							(end -0.1778 0.2794)
						)
						(arc
							(start 0.1778 0.2794)
							(mid 0.249642 0.249642)
							(end 0.2794 0.1778)
						)
						(arc
							(start 0.2794 -0.1778)
							(mid 0.249642 -0.249642)
							(end 0.1778 -0.2794)
						)
					)
					(width 0)
					(fill yes)
				)
			)
		)
		(pad "2" smd custom
			(at 0 0.4445 180)
			(size 0.1397 0.1397)
			(layers "F.Cu" "F.Mask" "F.Paste")
			(net "IO_EXP4_A0")
			(options
				(clearance outline)
				(anchor circle)
			)
			(primitives
				(gr_poly
					(pts
						(arc
							(start -0.1778 -0.2794)
							(mid -0.249642 -0.249642)
							(end -0.2794 -0.1778)
						)
						(arc
							(start -0.2794 0.1778)
							(mid -0.249642 0.249642)
							(end -0.1778 0.2794)
						)
						(arc
							(start 0.1778 0.2794)
							(mid 0.249642 0.249642)
							(end 0.2794 0.1778)
						)
						(arc
							(start 0.2794 -0.1778)
							(mid 0.249642 -0.249642)
							(end 0.1778 -0.2794)
						)
					)
					(width 0)
					(fill yes)
				)
			)
		)
	)
	(footprint ""
		(layer "F.Cu")
		(at 85.781134 -31.40837)
		(property "Reference" "R44"
			(at 0 0 0)
			(layer "F.SilkS")
			(hide yes)
			(effects
				(font
					(size 1.27 1.27)
				)
			)
		)
		(property "Value" "4K7R2F-GP"
			(at 0.064008 -3.993896 0)
			(unlocked yes)
			(layer "F.Fab")
			(hide yes)
			(effects
				(font
					(size 1.016 1.016)
					(thickness 0.1524)
				)
			)
		)
		(property "Device Type" "R402H16"
			(at 0.064008 -5.517896 0)
			(unlocked yes)
			(layer "F.Fab")
			(hide yes)
			(effects
				(font
					(size 1.016 1.016)
					(thickness 0.1524)
				)
			)
		)
		(duplicate_pad_numbers_are_jumpers no)
		(fp_line
			(start -0.508 -0.9398)
			(end -0.508 0.9398)
			(stroke
				(width 0.1524)
				(type default)
			)
			(layer "F.SilkS")
		)
		(fp_line
			(start 0.508 -0.9398)
			(end -0.508 -0.9398)
			(stroke
				(width 0.1524)
				(type default)
			)
			(layer "F.SilkS")
		)
		(fp_rect
			(start -0.508 0.9398)
			(end 0.508 -0.9398)
			(stroke
				(width 0)
				(type default)
			)
			(fill no)
			(layer "F.CrtYd")
		)
		(fp_rect
			(start -0.508 0.9398)
			(end 0.508 -0.9398)
			(stroke
				(width 0)
				(type default)
			)
			(fill no)
			(layer "F.Fab")
		)
		(pad "1" smd custom
			(at 0 -0.4445)
			(size 0.1397 0.1397)
			(layers "F.Cu" "F.Mask" "F.Paste")
			(net "P3V3_STBY_A")
			(options
				(clearance outline)
				(anchor circle)
			)
			(primitives
				(gr_poly
					(pts
						(arc
							(start -0.1778 -0.2794)
							(mid -0.249642 -0.249642)
							(end -0.2794 -0.1778)
						)
						(arc
							(start -0.2794 0.1778)
							(mid -0.249642 0.249642)
							(end -0.1778 0.2794)
						)
						(arc
							(start 0.1778 0.2794)
							(mid 0.249642 0.249642)
							(end 0.2794 0.1778)
						)
						(arc
							(start 0.2794 -0.1778)
							(mid 0.249642 -0.249642)
							(end 0.1778 -0.2794)
						)
					)
					(width 0)
					(fill yes)
				)
			)
		)
		(pad "2" smd custom
			(at 0 0.4445)
			(size 0.1397 0.1397)
			(layers "F.Cu" "F.Mask" "F.Paste")
			(net "IO_EXP10_A0")
			(options
				(clearance outline)
				(anchor circle)
			)
			(primitives
				(gr_poly
					(pts
						(arc
							(start -0.1778 -0.2794)
							(mid -0.249642 -0.249642)
							(end -0.2794 -0.1778)
						)
						(arc
							(start -0.2794 0.1778)
							(mid -0.249642 0.249642)
							(end -0.1778 0.2794)
						)
						(arc
							(start 0.1778 0.2794)
							(mid 0.249642 0.249642)
							(end 0.2794 0.1778)
						)
						(arc
							(start 0.2794 -0.1778)
							(mid 0.249642 -0.249642)
							(end 0.1778 -0.2794)
						)
					)
					(width 0)
					(fill yes)
				)
			)
		)
	)
)
